# S9S_MB_2U (Grand Teton) — schematic netlist excerpt (pin names and nets, part order shuffled) for the footprints in the layout excerpt that follows; sources: Cadence DE-HDL packaged netlist, KiCad conversion of 03242023_DA0F0TMBIJ0_F0T_Motherboard_J_brd_V01_OCP.brd

R4706  Q_RES  560 1% CHIP  pkg 0402LF  page 255 : A = LED_P12V_AUX_R3 ; B = P12V_AUX
JP16_23  TP  NA  pkg TP_BOM ONLY  page 312 : TP = NC
PD115  DIODE_TVS  SMF14A IC  pkg SOD123F  page 242 : A = GND ; C = P12V_AUX

(kicad_pcb
	(version 20260206)
	(generator "pcbnew")
	(generator_version "10.0")
	(general
		(thickness 1.6)
		(legacy_teardrops no)
	)
	(paper "A4")
	(title_block
		(title "03242023_DA0F0TMBIJ0_F0T_Motherboard_J_brd_V01_OCP.brd")
		(comment 1 "Grand Teton / footprints 412-414 of 6105")
	)
	(layers
		(0 "F.Cu" signal "TOP")
		(4 "In1.Cu" signal "GND")
		(6 "In2.Cu" signal "IN1")
		(8 "In3.Cu" signal "GND1")
		(10 "In4.Cu" signal "IN2")
		(12 "In5.Cu" signal "GND2")
		(14 "In6.Cu" signal "IN3")
		(16 "In7.Cu" signal "GND3")
		(18 "In8.Cu" signal "VCC")
		(20 "In9.Cu" signal "VCC1")
		(22 "In10.Cu" signal "GND4")
		(24 "In11.Cu" signal "IN4")
		(26 "In12.Cu" signal "GND5")
		(28 "In13.Cu" signal "IN5")
		(30 "In14.Cu" signal "GND6")
		(32 "In15.Cu" signal "IN6")
		(34 "In16.Cu" signal "GND7")
		(2 "B.Cu" signal "BOTTOM")
		(9 "F.Adhes" user "F.Adhesive")
		(11 "B.Adhes" user "B.Adhesive")
		(13 "F.Paste" user "Package Geometry/Pastemask Top")
		(15 "B.Paste" user "Package Geometry/Pastemask Bottom")
		(5 "F.SilkS" user "Ref Des/Silkscreen Top")
		(7 "B.SilkS" user "Ref Des/Silkscreen Bottom")
		(1 "F.Mask" user "Board Geometry/Soldermask Top")
		(3 "B.Mask" user "Board Geometry/Soldermask Bottom")
		(17 "Dwgs.User" user "User.Drawings")
		(19 "Cmts.User" user "User.Comments")
		(21 "Eco1.User" user "User.Eco1")
		(23 "Eco2.User" user "User.Eco2")
		(25 "Edge.Cuts" user "Board Geometry/Outline")
		(27 "Margin" user)
		(31 "F.CrtYd" user "Package Geometry/Place Bound Top")
		(29 "B.CrtYd" user "Package Geometry/Place Bound Bottom")
		(35 "F.Fab" user "Ref Des/Assembly Top")
		(33 "B.Fab" user "Ref Des/Assembly Bottom")
	)
	(footprint ""
		(layer "F.Cu")
		(at 369.7224 -74.3458 90)
		(property "Reference" "R4706"
			(at 0 0 90)
			(layer "F.SilkS")
			(hide yes)
			(effects
				(font
					(size 1.27 1.27)
				)
			)
		)
		(property "Value" ""
			(at 0 0 90)
			(layer "F.Fab")
			(effects
				(font
					(size 1.27 1.27)
				)
			)
		)
		(duplicate_pad_numbers_are_jumpers no)
		(fp_line
			(start 0.7874 -0.4064)
			(end 0.7874 0.4064)
			(stroke
				(width 0.1524)
				(type default)
			)
			(layer "F.SilkS")
		)
		(fp_line
			(start -0.7874 -0.4064)
			(end 0.7874 -0.4064)
			(stroke
				(width 0.1524)
				(type default)
			)
			(layer "F.SilkS")
		)
		(fp_line
			(start 0.7874 0.4064)
			(end -0.7874 0.4064)
			(stroke
				(width 0.1524)
				(type default)
			)
			(layer "F.SilkS")
		)
		(fp_line
			(start -0.7874 0.4064)
			(end -0.7874 -0.4064)
			(stroke
				(width 0.1524)
				(type default)
			)
			(layer "F.SilkS")
		)
		(fp_line
			(start -0.12065 -0.305054)
			(end -0.12065 -0.2794)
			(stroke
				(width 0.1)
				(type default)
			)
			(layer "F.Fab")
		)
		(fp_line
			(start -0.67945 -0.305054)
			(end -0.12065 -0.305054)
			(stroke
				(width 0.1)
				(type default)
			)
			(layer "F.Fab")
		)
		(fp_line
			(start 0.67945 -0.3048)
			(end 0.67945 0.3048)
			(stroke
				(width 0.1)
				(type default)
			)
			(layer "F.Fab")
		)
		(fp_line
			(start 0.12065 -0.3048)
			(end 0.67945 -0.3048)
			(stroke
				(width 0.1)
				(type default)
			)
			(layer "F.Fab")
		)
		(fp_line
			(start 0.12065 -0.2794)
			(end 0.12065 -0.3048)
			(stroke
				(width 0.1)
				(type default)
			)
			(layer "F.Fab")
		)
		(fp_line
			(start -0.12065 -0.2794)
			(end 0.12065 -0.2794)
			(stroke
				(width 0.1)
				(type default)
			)
			(layer "F.Fab")
		)
		(fp_line
			(start 0.120396 0.2794)
			(end -0.12065 0.2794)
			(stroke
				(width 0.1)
				(type default)
			)
			(layer "F.Fab")
		)
		(fp_line
			(start -0.12065 0.2794)
			(end -0.12065 0.3048)
			(stroke
				(width 0.1)
				(type default)
			)
			(layer "F.Fab")
		)
		(fp_line
			(start 0.67945 0.3048)
			(end 0.120396 0.3048)
			(stroke
				(width 0.1)
				(type default)
			)
			(layer "F.Fab")
		)
		(fp_line
			(start 0.120396 0.3048)
			(end 0.120396 0.2794)
			(stroke
				(width 0.1)
				(type default)
			)
			(layer "F.Fab")
		)
		(fp_line
			(start -0.12065 0.3048)
			(end -0.67945 0.3048)
			(stroke
				(width 0.1)
				(type default)
			)
			(layer "F.Fab")
		)
		(fp_line
			(start -0.67945 0.3048)
			(end -0.67945 -0.305054)
			(stroke
				(width 0.1)
				(type default)
			)
			(layer "F.Fab")
		)
		(pad "1" smd circle
			(at -0.40005 0 90)
			(size 0 0)
			(layers "F.Cu" "F.Mask" "F.Paste")
			(net "LED_P12V_AUX_R3")
		)
		(pad "2" smd circle
			(at 0.40005 0 90)
			(size 0 0)
			(layers "F.Cu" "F.Mask" "F.Paste")
			(net "P12V_AUX")
		)
	)
	(footprint ""
		(layer "F.Cu")
		(at 479.8695 -468.177372)
		(property "Reference" "JP16_23"
			(at -1.6764 -1.07823 0)
			(unlocked yes)
			(layer "F.SilkS")
			(effects
				(font
					(size 0.7874 0.5842)
					(thickness 0.1524)
				)
				(justify left)
			)
		)
		(property "Value" ""
			(at 0 0 0)
			(layer "F.Fab")
			(effects
				(font
					(size 1.27 1.27)
				)
			)
		)
		(duplicate_pad_numbers_are_jumpers no)
		(pad "1" smd circle
			(at 0 0)
			(size 0.762 0.762)
			(layers "F.Cu" "F.Mask" "F.Paste")
			(net "Net_8623")
		)
	)
	(footprint ""
		(layer "F.Cu")
		(at 191.065404 -32.110426 180)
		(property "Reference" "PD115"
			(at 9.013444 0.703072 0)
			(unlocked yes)
			(layer "F.SilkS")
			(effects
				(font
					(size 0.7874 0.5842)
					(thickness 0.1524)
				)
				(justify left)
			)
		)
		(property "Value" ""
			(at 0 0 180)
			(layer "F.Fab")
			(effects
				(font
					(size 1.27 1.27)
				)
			)
		)
		(duplicate_pad_numbers_are_jumpers no)
		(fp_line
			(start 2.631186 0.999998)
			(end 2.631186 -0.999998)
			(stroke
				(width 0.1524)
				(type default)
			)
			(layer "F.SilkS")
		)
		(fp_line
			(start 2.631186 -0.999998)
			(end -2.250186 -0.999998)
			(stroke
				(width 0.1524)
				(type default)
			)
			(layer "F.SilkS")
		)
		(fp_line
			(start 0.381 -0.0508)
			(end 0.635 -0.0508)
			(stroke
				(width 0.1524)
				(type default)
			)
			(layer "F.SilkS")
		)
		(fp_line
			(start 0.381 -0.0508)
			(end -0.381 0.3302)
			(stroke
				(width 0.1524)
				(type default)
			)
			(layer "F.SilkS")
		)
		(fp_line
			(start 0.381 -0.4318)
			(end 0.381 0.3302)
			(stroke
				(width 0.1524)
				(type default)
			)
			(layer "F.SilkS")
		)
		(fp_line
			(start -0.381 0.3302)
			(end -0.381 -0.4318)
			(stroke
				(width 0.1524)
				(type default)
			)
			(layer "F.SilkS")
		)
		(fp_line
			(start -0.381 -0.0508)
			(end -0.6604 -0.0508)
			(stroke
				(width 0.1524)
				(type default)
			)
			(layer "F.SilkS")
		)
		(fp_line
			(start -0.381 -0.4318)
			(end 0.381 -0.0508)
			(stroke
				(width 0.1524)
				(type default)
			)
			(layer "F.SilkS")
		)
		(fp_line
			(start -2.250186 0.999998)
			(end 2.631186 0.999998)
			(stroke
				(width 0.1524)
				(type default)
			)
			(layer "F.SilkS")
		)
		(fp_line
			(start -2.250186 -0.999998)
			(end -2.250186 0.999998)
			(stroke
				(width 0.1524)
				(type default)
			)
			(layer "F.SilkS")
		)
		(fp_rect
			(start 2.6162 -0.9652)
			(end 2.1844 1.016)
			(stroke
				(width 0)
				(type default)
			)
			(fill yes)
			(layer "F.SilkS")
		)
		(fp_line
			(start 1.450086 0.999998)
			(end 1.450086 -0.999998)
			(stroke
				(width 0.1)
				(type default)
			)
			(layer "F.Fab")
		)
		(fp_line
			(start 1.450086 -0.999998)
			(end -1.450086 -0.999998)
			(stroke
				(width 0.1)
				(type default)
			)
			(layer "F.Fab")
		)
		(fp_line
			(start -1.450086 0.999998)
			(end 1.450086 0.999998)
			(stroke
				(width 0.1)
				(type default)
			)
			(layer "F.Fab")
		)
		(fp_line
			(start -1.450086 -0.999998)
			(end -1.450086 0.999998)
			(stroke
				(width 0.1)
				(type default)
			)
			(layer "F.Fab")
		)
		(fp_text user "-"
			(at 2.4384 -0.22225 180)
			(unlocked yes)
			(layer "F.SilkS")
			(effects
				(font
					(size 1.905 1.4224)
					(thickness 0.1524)
				)
				(justify left)
			)
		)
		(fp_text user "+"
			(at -4.021836 -0.429768 180)
			(unlocked yes)
			(layer "F.SilkS")
			(effects
				(font
					(size 1.905 1.4224)
					(thickness 0.1524)
				)
				(justify left)
			)
		)
		(fp_text user "-"
			(at 2.4384 -0.22225 180)
			(unlocked yes)
			(layer "F.Fab")
			(effects
				(font
					(size 1.905 1.4224)
					(thickness 0.1524)
				)
				(justify left)
			)
		)
		(fp_text user "+"
			(at -3.4798 -0.22225 180)
			(unlocked yes)
			(layer "F.Fab")
			(effects
				(font
					(size 1.905 1.4224)
					(thickness 0.1524)
				)
				(justify left)
			)
		)
		(pad "A" smd rect
			(at -1.450086 0 180)
			(size 1.3208 1.4224)
			(layers "F.Cu" "F.Mask" "F.Paste")
			(net "GND")
		)
		(pad "C" smd rect
			(at 1.450086 0 180)
			(size 1.3208 1.4224)
			(layers "F.Cu" "F.Mask" "F.Paste")
			(net "P12V_AUX")
		)
	)
)
